(kicad_pcb
	(version 20260206)
	(generator "pcbnew")
	(generator_version "10.0")
	(general
		(thickness 1.6)
		(legacy_teardrops no)
	)
	(paper "A4")
	(title_block
		(title "12092022_DA0F0TFB6D0_F0T_FAN_BOARD_MP5048_D_brd_v02_OCP.brd")
		(comment 1 "Grand Teton / footprints 915-917 of 924")
	)
	(layers
		(0 "F.Cu" signal "TOP")
		(4 "In1.Cu" signal "GND")
		(6 "In2.Cu" signal "IN1")
		(8 "In3.Cu" signal "IN2")
		(10 "In4.Cu" signal "GND1")
		(2 "B.Cu" signal "BOTTOM")
		(9 "F.Adhes" user "F.Adhesive")
		(11 "B.Adhes" user "B.Adhesive")
		(13 "F.Paste" user "Package Geometry/Pastemask Top")
		(15 "B.Paste" user "Package Geometry/Pastemask Bottom")
		(5 "F.SilkS" user "Ref Des/Silkscreen Top")
		(7 "B.SilkS" user "Ref Des/Silkscreen Bottom")
		(1 "F.Mask" user "Board Geometry/Soldermask Top")
		(3 "B.Mask" user "Board Geometry/Soldermask Bottom")
		(17 "Dwgs.User" user "User.Drawings")
		(19 "Cmts.User" user "User.Comments")
		(21 "Eco1.User" user "User.Eco1")
		(23 "Eco2.User" user "User.Eco2")
		(25 "Edge.Cuts" user "Board Geometry/Outline")
		(27 "Margin" user)
		(31 "F.CrtYd" user "Package Geometry/Place Bound Top")
		(29 "B.CrtYd" user "Package Geometry/Place Bound Bottom")
		(35 "F.Fab" user "Ref Des/Assembly Top")
		(33 "B.Fab" user "Ref Des/Assembly Bottom")
	)
	(footprint ""
		(layer "B.Cu")
		(at 12.446 -73.9648 90)
		(property "Reference" "PC44"
			(at 0 0 90)
			(layer "B.SilkS")
			(hide yes)
			(effects
				(font
					(size 1.27 1.27)
				)
				(justify mirror)
			)
		)
		(property "Value" ""
			(at 0 0 90)
			(layer "B.Fab")
			(effects
				(font
					(size 1.27 1.27)
				)
				(justify mirror)
			)
		)
		(duplicate_pad_numbers_are_jumpers no)
		(fp_line
			(start 0.7874 -0.4064)
			(end -0.7874 -0.4064)
			(stroke
				(width 0.1524)
				(type default)
			)
			(layer "B.SilkS")
		)
		(fp_line
			(start -0.7874 -0.4064)
			(end -0.7874 0.4064)
			(stroke
				(width 0.1524)
				(type default)
			)
			(layer "B.SilkS")
		)
		(fp_line
			(start 0.7874 0.4064)
			(end 0.7874 -0.4064)
			(stroke
				(width 0.1524)
				(type default)
			)
			(layer "B.SilkS")
		)
		(fp_line
			(start -0.7874 0.4064)
			(end 0.7874 0.4064)
			(stroke
				(width 0.1524)
				(type default)
			)
			(layer "B.SilkS")
		)
		(fp_line
			(start 0.67945 -0.305054)
			(end 0.12065 -0.305054)
			(stroke
				(width 0.1)
				(type default)
			)
			(layer "B.Fab")
		)
		(fp_line
			(start 0.12065 -0.305054)
			(end 0.12065 -0.2794)
			(stroke
				(width 0.1)
				(type default)
			)
			(layer "B.Fab")
		)
		(fp_line
			(start -0.12065 -0.3048)
			(end -0.67945 -0.3048)
			(stroke
				(width 0.1)
				(type default)
			)
			(layer "B.Fab")
		)
		(fp_line
			(start -0.67945 -0.3048)
			(end -0.67945 0.3048)
			(stroke
				(width 0.1)
				(type default)
			)
			(layer "B.Fab")
		)
		(fp_line
			(start 0.12065 -0.2794)
			(end -0.12065 -0.2794)
			(stroke
				(width 0.1)
				(type default)
			)
			(layer "B.Fab")
		)
		(fp_line
			(start -0.12065 -0.2794)
			(end -0.12065 -0.3048)
			(stroke
				(width 0.1)
				(type default)
			)
			(layer "B.Fab")
		)
		(fp_line
			(start 0.12065 0.2794)
			(end 0.12065 0.3048)
			(stroke
				(width 0.1)
				(type default)
			)
			(layer "B.Fab")
		)
		(fp_line
			(start -0.120396 0.2794)
			(end 0.12065 0.2794)
			(stroke
				(width 0.1)
				(type default)
			)
			(layer "B.Fab")
		)
		(fp_line
			(start 0.67945 0.3048)
			(end 0.67945 -0.305054)
			(stroke
				(width 0.1)
				(type default)
			)
			(layer "B.Fab")
		)
		(fp_line
			(start 0.12065 0.3048)
			(end 0.67945 0.3048)
			(stroke
				(width 0.1)
				(type default)
			)
			(layer "B.Fab")
		)
		(fp_line
			(start -0.120396 0.3048)
			(end -0.120396 0.2794)
			(stroke
				(width 0.1)
				(type default)
			)
			(layer "B.Fab")
		)
		(fp_line
			(start -0.67945 0.3048)
			(end -0.120396 0.3048)
			(stroke
				(width 0.1)
				(type default)
			)
			(layer "B.Fab")
		)
		(pad "1" smd circle
			(at 0.40005 0 270)
			(size 0 0)
			(layers "B.Cu" "B.Mask" "B.Paste")
			(net "FAN_5_P3V_R")
		)
		(pad "2" smd circle
			(at -0.40005 0 270)
			(size 0 0)
			(layers "B.Cu" "B.Mask" "B.Paste")
			(net "GND")
		)
	)
	(footprint ""
		(layer "B.Cu")
		(at 14.382242 -264.404856 180)
		(property "Reference" "PU9"
			(at -6.191758 -2.430526 0)
			(unlocked yes)
			(layer "B.SilkS")
			(effects
				(font
					(size 0.7874 0.5842)
					(thickness 0.1524)
				)
				(justify left mirror)
			)
		)
		(property "Value" ""
			(at 0 0 0)
			(layer "B.Fab")
			(effects
				(font
					(size 1.27 1.27)
				)
				(justify mirror)
			)
		)
		(duplicate_pad_numbers_are_jumpers no)
		(fp_line
			(start 2.549906 2.549906)
			(end 2.4384 2.549906)
			(stroke
				(width 0.1524)
				(type default)
			)
			(layer "B.SilkS")
		)
		(fp_line
			(start 2.549906 2.2352)
			(end 2.549906 2.549906)
			(stroke
				(width 0.1524)
				(type default)
			)
			(layer "B.SilkS")
		)
		(fp_line
			(start 2.549906 1.4986)
			(end 2.549906 1.7526)
			(stroke
				(width 0.1524)
				(type default)
			)
			(layer "B.SilkS")
		)
		(fp_line
			(start 2.549906 0.6858)
			(end 2.549906 0.9144)
			(stroke
				(width 0.1524)
				(type default)
			)
			(layer "B.SilkS")
		)
		(fp_line
			(start 2.549906 -0.9144)
			(end 2.549906 0.1016)
			(stroke
				(width 0.1524)
				(type default)
			)
			(layer "B.SilkS")
		)
		(fp_line
			(start 2.549906 -1.7526)
			(end 2.549906 -1.4986)
			(stroke
				(width 0.1524)
				(type default)
			)
			(layer "B.SilkS")
		)
		(fp_line
			(start 2.549906 -2.549906)
			(end 2.549906 -2.2352)
			(stroke
				(width 0.1524)
				(type default)
			)
			(layer "B.SilkS")
		)
		(fp_line
			(start 2.4384 -2.549906)
			(end 2.549906 -2.549906)
			(stroke
				(width 0.1524)
				(type default)
			)
			(layer "B.SilkS")
		)
		(fp_line
			(start 2.199894 -3.9624)
			(end 2.199894 -2.9464)
			(stroke
				(width 0.1524)
				(type default)
			)
			(layer "B.SilkS")
		)
		(fp_line
			(start 1.800098 2.9464)
			(end 1.800098 3.4544)
			(stroke
				(width 0.1524)
				(type default)
			)
			(layer "B.SilkS")
		)
		(fp_line
			(start 0.199898 -3.4544)
			(end 0.199898 -2.9464)
			(stroke
				(width 0.1524)
				(type default)
			)
			(layer "B.SilkS")
		)
		(fp_line
			(start -0.199898 2.9464)
			(end -0.199898 3.9624)
			(stroke
				(width 0.1524)
				(type default)
			)
			(layer "B.SilkS")
		)
		(fp_line
			(start -1.800098 -3.9624)
			(end -1.800098 -2.9464)
			(stroke
				(width 0.1524)
				(type default)
			)
			(layer "B.SilkS")
		)
		(fp_line
			(start -2.199894 2.9464)
			(end -2.199894 3.4544)
			(stroke
				(width 0.1524)
				(type default)
			)
			(layer "B.SilkS")
		)
		(fp_line
			(start -2.4384 2.549906)
			(end -2.549906 2.549906)
			(stroke
				(width 0.1524)
				(type default)
			)
			(layer "B.SilkS")
		)
		(fp_line
			(start -2.549906 2.549906)
			(end -2.549906 2.2352)
			(stroke
				(width 0.1524)
				(type default)
			)
			(layer "B.SilkS")
		)
		(fp_line
			(start -2.549906 1.7526)
			(end -2.549906 1.4986)
			(stroke
				(width 0.1524)
				(type default)
			)
			(layer "B.SilkS")
		)
		(fp_line
			(start -2.549906 0.9144)
			(end -2.549906 -0.1016)
			(stroke
				(width 0.1524)
				(type default)
			)
			(layer "B.SilkS")
		)
		(fp_line
			(start -2.549906 -0.6858)
			(end -2.549906 -0.9144)
			(stroke
				(width 0.1524)
				(type default)
			)
			(layer "B.SilkS")
		)
		(fp_line
			(start -2.549906 -1.4986)
			(end -2.549906 -1.7526)
			(stroke
				(width 0.1524)
				(type default)
			)
			(layer "B.SilkS")
		)
		(fp_line
			(start -2.549906 -2.2352)
			(end -2.549906 -2.549906)
			(stroke
				(width 0.1524)
				(type default)
			)
			(layer "B.SilkS")
		)
		(fp_line
			(start -2.549906 -2.549906)
			(end -2.4384 -2.549906)
			(stroke
				(width 0.1524)
				(type default)
			)
			(layer "B.SilkS")
		)
		(fp_poly
			(pts
				(xy 3.565398 -1.513078) (xy 2.939034 -1.199896) (xy 3.565398 -0.886968)
			)
			(stroke
				(width 0)
				(type default)
			)
			(fill yes)
			(layer "B.SilkS")
		)
		(fp_line
			(start 2.549906 2.549906)
			(end -2.549906 2.549906)
			(stroke
				(width 0.1)
				(type default)
			)
			(layer "B.Fab")
		)
		(fp_line
			(start 2.549906 -2.549906)
			(end 2.549906 2.549906)
			(stroke
				(width 0.1)
				(type default)
			)
			(layer "B.Fab")
		)
		(fp_line
			(start 2.199894 -3.9624)
			(end 2.199894 -2.9464)
			(stroke
				(width 0.1)
				(type default)
			)
			(layer "B.Fab")
		)
		(fp_line
			(start 1.800098 2.9464)
			(end 1.800098 3.4544)
			(stroke
				(width 0.1)
				(type default)
			)
			(layer "B.Fab")
		)
		(fp_line
			(start 0.199898 -3.4544)
			(end 0.199898 -2.9464)
			(stroke
				(width 0.1)
				(type default)
			)
			(layer "B.Fab")
		)
		(fp_line
			(start -0.199898 2.9464)
			(end -0.199898 3.9624)
			(stroke
				(width 0.1)
				(type default)
			)
			(layer "B.Fab")
		)
		(fp_line
			(start -1.800098 -3.9624)
			(end -1.800098 -2.9464)
			(stroke
				(width 0.1)
				(type default)
			)
			(layer "B.Fab")
		)
		(fp_line
			(start -2.199894 2.9464)
			(end -2.199894 3.4544)
			(stroke
				(width 0.1)
				(type default)
			)
			(layer "B.Fab")
		)
		(fp_line
			(start -2.549906 2.549906)
			(end -2.549906 -2.549906)
			(stroke
				(width 0.1)
				(type default)
			)
			(layer "B.Fab")
		)
		(fp_line
			(start -2.549906 -2.549906)
			(end 2.549906 -2.549906)
			(stroke
				(width 0.1)
				(type default)
			)
			(layer "B.Fab")
		)
		(fp_poly
			(pts
				(xy 3.7084 -1.584706) (xy 2.939034 -1.199896) (xy 3.7084 -0.81534)
			)
			(stroke
				(width 0)
				(type default)
			)
			(fill yes)
			(layer "B.Fab")
		)
		(fp_text user "3"
			(at 3.333242 1.183894 0)
			(unlocked yes)
			(layer "B.SilkS")
			(effects
				(font
					(size 0.635 0.4064)
					(thickness 0.1524)
				)
				(justify mirror)
			)
		)
		(fp_text user "30"
			(at 2.952242 -3.134106 0)
			(unlocked yes)
			(layer "B.SilkS")
			(effects
				(font
					(size 0.635 0.4064)
					(thickness 0.1524)
				)
				(justify mirror)
			)
		)
		(fp_text user "4"
			(at 2.825242 3.215894 0)
			(unlocked yes)
			(layer "B.SilkS")
			(effects
				(font
					(size 0.635 0.4064)
					(thickness 0.1524)
				)
				(justify mirror)
			)
		)
		(fp_text user "15"
			(at -3.016758 3.088894 0)
			(unlocked yes)
			(layer "B.SilkS")
			(effects
				(font
					(size 0.635 0.4064)
					(thickness 0.1524)
				)
				(justify mirror)
			)
		)
		(fp_text user "19"
			(at -3.016758 -3.007106 0)
			(unlocked yes)
			(layer "B.SilkS")
			(effects
				(font
					(size 0.635 0.4064)
					(thickness 0.1524)
				)
				(justify mirror)
			)
		)
		(fp_text user "16"
			(at -3.429508 1.152144 270)
			(unlocked yes)
			(layer "B.SilkS")
			(effects
				(font
					(size 0.635 0.4064)
					(thickness 0.1524)
				)
				(justify mirror)
			)
		)
		(fp_text user "18"
			(at -3.429508 -1.387856 270)
			(unlocked yes)
			(layer "B.SilkS")
			(effects
				(font
					(size 0.635 0.4064)
					(thickness 0.1524)
				)
				(justify mirror)
			)
		)
		(fp_text user "3"
			(at 3.299968 1.1938 90)
			(unlocked yes)
			(layer "B.Fab")
			(effects
				(font
					(size 0.635 0.4064)
					(thickness 0.1524)
				)
				(justify mirror)
			)
		)
		(fp_text user "30"
			(at 2.9464 -3.045968 180)
			(unlocked yes)
			(layer "B.Fab")
			(effects
				(font
					(size 0.635 0.4064)
					(thickness 0.1524)
				)
				(justify mirror)
			)
		)
		(fp_text user "4"
			(at 2.6416 3.151632 180)
			(unlocked yes)
			(layer "B.Fab")
			(effects
				(font
					(size 0.635 0.4064)
					(thickness 0.1524)
				)
				(justify mirror)
			)
		)
		(fp_text user "19"
			(at -2.8448 -3.096768 180)
			(unlocked yes)
			(layer "B.Fab")
			(effects
				(font
					(size 0.635 0.4064)
					(thickness 0.1524)
				)
				(justify mirror)
			)
		)
		(fp_text user "15"
			(at -2.8956 3.126232 180)
			(unlocked yes)
			(layer "B.Fab")
			(effects
				(font
					(size 0.635 0.4064)
					(thickness 0.1524)
				)
				(justify mirror)
			)
		)
		(fp_text user "18"
			(at -3.304032 -1.2192 90)
			(unlocked yes)
			(layer "B.Fab")
			(effects
				(font
					(size 0.635 0.4064)
					(thickness 0.1524)
				)
				(justify mirror)
			)
		)
		(fp_text user "16"
			(at -3.329432 1.2192 90)
			(unlocked yes)
			(layer "B.Fab")
			(effects
				(font
					(size 0.635 0.4064)
					(thickness 0.1524)
				)
				(justify mirror)
			)
		)
		(pad "1" smd circle
			(at 1.599946 -1.199896 90)
			(size 0 0)
			(layers "B.Cu" "B.Mask" "B.Paste")
			(net "P52V_HSC")
		)
		(pad "2" smd rect
			(at 1.549908 0.40005 270)
			(size 0.3048 2.5146)
			(layers "B.Cu" "B.Mask" "B.Paste")
			(net "P52V_HSC")
		)
		(pad "3" smd rect
			(at 1.549908 1.199896 270)
			(size 0.3048 2.5146)
			(layers "B.Cu" "B.Mask" "B.Paste")
			(net "P52V_FAN_7")
		)
		(pad "4" smd circle
			(at 2.199894 2.350008 180)
			(size 0 0)
			(layers "B.Cu" "B.Mask" "B.Paste")
			(net "P52V_FAN_7")
		)
		(pad "5" smd rect
			(at 1.800098 2.350008)
			(size 0.1778 0.9144)
			(layers "B.Cu" "B.Mask" "B.Paste")
			(net "P52V_FAN_7")
		)
		(pad "6" smd rect
			(at 1.400048 2.350008)
			(size 0.1778 0.9144)
			(layers "B.Cu" "B.Mask" "B.Paste")
			(net "P52V_FAN_7")
		)
		(pad "7" smd rect
			(at 0.999998 2.350008)
			(size 0.1778 0.9144)
			(layers "B.Cu" "B.Mask" "B.Paste")
			(net "P52V_FAN_7")
		)
		(pad "8" smd rect
			(at 0.599948 2.350008)
			(size 0.1778 0.9144)
			(layers "B.Cu" "B.Mask" "B.Paste")
			(net "P52V_FAN_7")
		)
		(pad "9" smd rect
			(at 0.199898 2.350008)
			(size 0.1778 0.9144)
			(layers "B.Cu" "B.Mask" "B.Paste")
			(net "P52V_FAN_7")
		)
		(pad "10" smd rect
			(at -0.199898 2.350008)
			(size 0.1778 0.9144)
			(layers "B.Cu" "B.Mask" "B.Paste")
			(net "P52V_FAN_7")
		)
		(pad "11" smd rect
			(at -0.599948 2.350008)
			(size 0.1778 0.9144)
			(layers "B.Cu" "B.Mask" "B.Paste")
			(net "P52V_FAN_7")
		)
		(pad "12" smd rect
			(at -0.999998 2.350008)
			(size 0.1778 0.9144)
			(layers "B.Cu" "B.Mask" "B.Paste")
			(net "P52V_FAN_7")
		)
		(pad "13" smd rect
			(at -1.400048 2.350008)
			(size 0.1778 0.9144)
			(layers "B.Cu" "B.Mask" "B.Paste")
			(net "P52V_FAN_7")
		)
		(pad "14" smd rect
			(at -1.800098 2.350008)
			(size 0.1778 0.9144)
			(layers "B.Cu" "B.Mask" "B.Paste")
			(net "P52V_FAN_7")
		)
		(pad "15" smd circle
			(at -2.199894 2.350008 180)
			(size 0 0)
			(layers "B.Cu" "B.Mask" "B.Paste")
			(net "P52V_FAN_7")
		)
		(pad "16" smd rect
			(at -1.549908 1.199896 270)
			(size 0.3048 2.5146)
			(layers "B.Cu" "B.Mask" "B.Paste")
			(net "P52V_FAN_7")
		)
		(pad "17" smd rect
			(at -1.549908 -0.40005 270)
			(size 0.3048 2.5146)
			(layers "B.Cu" "B.Mask" "B.Paste")
			(net "P52V_FAN_7")
		)
		(pad "18" smd rect
			(at -1.549908 -1.199896 270)
			(size 0.3048 2.5146)
			(layers "B.Cu" "B.Mask" "B.Paste")
			(net "P52V_HSC")
		)
		(pad "19" smd circle
			(at -2.199894 -2.350008)
			(size 0 0)
			(layers "B.Cu" "B.Mask" "B.Paste")
			(net "FAN_7_CS")
		)
		(pad "20" smd rect
			(at -1.800098 -2.350008)
			(size 0.1778 0.9144)
			(layers "B.Cu" "B.Mask" "B.Paste")
			(net "FAN_7_IMON")
		)
		(pad "21" smd rect
			(at -1.400048 -2.350008)
			(size 0.1778 0.9144)
			(layers "B.Cu" "B.Mask" "B.Paste")
			(net "FAN_7_SS")
		)
		(pad "22" smd rect
			(at -0.999998 -2.350008)
			(size 0.1778 0.9144)
			(layers "B.Cu" "B.Mask" "B.Paste")
			(net "FAN_7_FAULT")
		)
		(pad "23" smd rect
			(at -0.599948 -2.350008)
			(size 0.1778 0.9144)
			(layers "B.Cu" "B.Mask" "B.Paste")
			(net "FAN_7_TIMER")
		)
		(pad "24" smd rect
			(at -0.199898 -2.350008)
			(size 0.1778 0.9144)
			(layers "B.Cu" "B.Mask" "B.Paste")
			(net "FAN_7_CLREF")
		)
		(pad "25" smd rect
			(at 0.199898 -2.350008)
			(size 0.1778 0.9144)
			(layers "B.Cu" "B.Mask" "B.Paste")
			(net "GND")
		)
		(pad "26" smd rect
			(at 0.599948 -2.350008)
			(size 0.1778 0.9144)
			(layers "B.Cu" "B.Mask" "B.Paste")
			(net "FAN_7_ON")
		)
		(pad "27" smd rect
			(at 0.999998 -2.350008)
			(size 0.1778 0.9144)
			(layers "B.Cu" "B.Mask" "B.Paste")
			(net "FAN_7_P3V_R")
		)
		(pad "28" smd rect
			(at 1.400048 -2.350008)
			(size 0.1778 0.9144)
			(layers "B.Cu" "B.Mask" "B.Paste")
			(net "FAN_7_P5V")
		)
		(pad "29" smd rect
			(at 1.800098 -2.350008)
			(size 0.1778 0.9144)
			(layers "B.Cu" "B.Mask" "B.Paste")
			(net "FAN_7_TEMP")
		)
		(pad "30" smd circle
			(at 2.199894 -2.350008)
			(size 0 0)
			(layers "B.Cu" "B.Mask" "B.Paste")
			(net "FAN_7_MODE")
		)
	)
	(footprint ""
		(layer "B.Cu")
		(at 16.782796 -277.431754 180)
		(property "Reference" "C2117"
			(at 0 0 0)
			(layer "B.SilkS")
			(hide yes)
			(effects
				(font
					(size 1.27 1.27)
				)
				(justify mirror)
			)
		)
		(property "Value" ""
			(at 0 0 0)
			(layer "B.Fab")
			(effects
				(font
					(size 1.27 1.27)
				)
				(justify mirror)
			)
		)
		(duplicate_pad_numbers_are_jumpers no)
		(fp_line
			(start 2.2098 0.9398)
			(end 2.2098 -0.9398)
			(stroke
				(width 0.1524)
				(type default)
			)
			(layer "B.SilkS")
		)
		(fp_line
			(start 2.2098 -0.9398)
			(end -2.2098 -0.9398)
			(stroke
				(width 0.1524)
				(type default)
			)
			(layer "B.SilkS")
		)
		(fp_line
			(start -2.2098 0.9398)
			(end 2.2098 0.9398)
			(stroke
				(width 0.1524)
				(type default)
			)
			(layer "B.SilkS")
		)
		(fp_line
			(start -2.2098 -0.9398)
			(end -2.2098 0.9398)
			(stroke
				(width 0.1524)
				(type default)
			)
			(layer "B.SilkS")
		)
		(fp_line
			(start 1.700022 0.899922)
			(end 1.700022 -0.899922)
			(stroke
				(width 0.1)
				(type default)
			)
			(layer "B.Fab")
		)
		(fp_line
			(start 1.700022 -0.899922)
			(end -1.700022 -0.899922)
			(stroke
				(width 0.1)
				(type default)
			)
			(layer "B.Fab")
		)
		(fp_line
			(start -1.700022 0.899922)
			(end 1.700022 0.899922)
			(stroke
				(width 0.1)
				(type default)
			)
			(layer "B.Fab")
		)
		(fp_line
			(start -1.700022 -0.899922)
			(end -1.700022 0.899922)
			(stroke
				(width 0.1)
				(type default)
			)
			(layer "B.Fab")
		)
		(pad "1" smd rect
			(at 1.4732 0 180)
			(size 1.1684 1.5748)
			(layers "B.Cu" "B.Mask" "B.Paste")
			(net "P52V_FAN_7")
		)
		(pad "2" smd rect
			(at -1.4732 0 180)
			(size 1.1684 1.5748)
			(layers "B.Cu" "B.Mask" "B.Paste")
			(net "GND")
		)
	)
)
